# S9S_MB_2U (Grand Teton) — schematic netlist excerpt (pin names and nets, part order shuffled) for the footprints in the layout excerpt that follows; sources: Cadence DE-HDL packaged netlist, KiCad conversion of 03242023_DA0F0TMBIJ0_F0T_Motherboard_J_brd_V01_OCP.brd

J37  SCONN168_ME1016810202011  IO  pkg CON_F168S2H7D_P0-6W2-95_LUH  page 153
  GND_A1  = GND
  GND_A2  = GND
  GND_A3  = GND
  GND_A4  = GND
  GND_A5  = GND
  GND_A6  = GND
  SMCLK  = SMB_OCP_SFF_3V3AUX_BUF_R_SCL
  SMDAT  = SMB_OCP_SFF_3V3AUX_BUF_R_SDA
  \smrst#\  = RST_SMB_OCP_SFF_N
  \prsnta#\  = OCP_SFF_PRSNTA_R_N
  \perst1#\  = RST_PERST1_OCP_SFF_N
  \prsntb2#\  = OCP_SFF_PRSNT2_R_N
  GND_A13  = GND
  REFCLKN1  = CLK_100M_OCP_SFF_1_DN
  REFCLKP1  = CLK_100M_OCP_SFF_1_DP
  GND_A16  = GND
  PERN0  = P5E_CPU0_PE1_RX_DN<0>
  PERP0  = P5E_CPU0_PE1_RX_DP<0>
  GND_A19  = GND
  PERN1  = P5E_CPU0_PE1_RX_DP<1>
  PERP1  = P5E_CPU0_PE1_RX_DN<1>
  GND_A22  = GND
  PERN2  = P5E_CPU0_PE1_RX_DP<2>
  PERP2  = P5E_CPU0_PE1_RX_DN<2>
  GND_A25  = GND
  PERN3  = P5E_CPU0_PE1_RX_DP<3>
  PERP3  = P5E_CPU0_PE1_RX_DN<3>
  GND_A28  = GND
  GND_A29  = GND
  PERN4  = P5E_CPU0_PE1_RX_DP<4>
  PERP4  = P5E_CPU0_PE1_RX_DN<4>
  GND_A32  = GND
  PERN5  = P5E_CPU0_PE1_RX_DP<5>
  PERP5  = P5E_CPU0_PE1_RX_DN<5>
  GND_A35  = GND
  PERN6  = P5E_CPU0_PE1_RX_DP<6>
  PERP6  = P5E_CPU0_PE1_RX_DN<6>
  GND_A38  = GND
  PERN7  = P5E_CPU0_PE1_RX_DP<7>
  PERP7  = P5E_CPU0_PE1_RX_DN<7>
  GND_A41  = GND
  \prsntb1#\  = OCP_SFF_PRSNT1_R_N
  GND_A43  = GND
  PERN8  = P5E_CPU0_PE1_RX_DP<8>
  PERP8  = P5E_CPU0_PE1_RX_DN<8>
  GND_A46  = GND
  PERN9  = P5E_CPU0_PE1_RX_DP<9>
  PERP9  = P5E_CPU0_PE1_RX_DN<9>
  GND_A49  = GND
  PERN10  = P5E_CPU0_PE1_RX_DP<10>
  PERP10  = P5E_CPU0_PE1_RX_DN<10>
  GND_A52  = GND
  PERN11  = P5E_CPU0_PE1_RX_DP<11>
  PERP11  = P5E_CPU0_PE1_RX_DN<11>
  GND_A55  = GND
  PERN12  = P5E_CPU0_PE1_RX_DP<12>
  PERP12  = P5E_CPU0_PE1_RX_DN<12>
  GND_A58  = GND
  PERN13  = P5E_CPU0_PE1_RX_DP<13>
  PERP13  = P5E_CPU0_PE1_RX_DN<13>
  GND_A61  = GND
  PERN14  = P5E_CPU0_PE1_RX_DP<14>
  PERP14  = P5E_CPU0_PE1_RX_DN<14>
  GND_A64  = GND
  PERN15  = P5E_CPU0_PE1_RX_DP<15>
  PERP15  = P5E_CPU0_PE1_RX_DN<15>
  GND_A67  = GND
  USB_DATN  = OCP_SFF_USB2_3_DN
  USB_DATP  = OCP_SFF_USB2_3_DP
  \pwrbrk0#\  = OCP_SFF_PWRBRK_N
  \+12v_edge_b1\  = P12V_OCP_SFF
  \+12v_edge_b2\  = P12V_OCP_SFF
  \+12v_edge_b3\  = P12V_OCP_SFF
  \+12v_edge_b4\  = P12V_OCP_SFF
  \+12v_edge_b5\  = P12V_OCP_SFF
  \+12v_edge_b6\  = P12V_OCP_SFF
  \bif0#\  = OCP_SFF_BIF0_R_N
  \bif1#\  = OCP_SFF_BIF1_R_N
  \bif2#\  = OCP_SFF_BIF2_R_N
  \perst0#\  = RST_PERST0_OCP_SFF_N
  \+3.3v_edge\  = P3V3_OCP_SFF
  AUX_PWR_EN  = OCP_SFF_AUX_PWR_EN_R
  GND_B13  = GND
  REFCLKN0  = CLK_100M_OCP_SFF_0_DN
  REFCLKP0  = CLK_100M_OCP_SFF_0_DP
  GND_B16  = GND
  PETN0  = P5E_CPU0_PE1_TX_C_DN<0>
  PETP0  = P5E_CPU0_PE1_TX_C_DP<0>
  GND_B19  = GND
  PETN1  = P5E_CPU0_PE1_TX_C_DN<1>
  PETP1  = P5E_CPU0_PE1_TX_C_DP<1>
  GND_B22  = GND
  PETN2  = P5E_CPU0_PE1_TX_C_DP<2>
  PETP2  = P5E_CPU0_PE1_TX_C_DN<2>
  GND_B25  = GND
  PETN3  = P5E_CPU0_PE1_TX_C_DN<3>
  PETP3  = P5E_CPU0_PE1_TX_C_DP<3>
  GND_B28  = GND
  GND_B29  = GND
  PETN4  = P5E_CPU0_PE1_TX_C_DP<4>
  PETP4  = P5E_CPU0_PE1_TX_C_DN<4>
  GND_B32  = GND
  PETN5  = P5E_CPU0_PE1_TX_C_DN<5>
  PETP5  = P5E_CPU0_PE1_TX_C_DP<5>
  GND_B35  = GND
  PETN6  = P5E_CPU0_PE1_TX_C_DP<6>
  PETP6  = P5E_CPU0_PE1_TX_C_DN<6>
  GND_B38  = GND
  PETN7  = P5E_CPU0_PE1_TX_C_DN<7>
  PETP7  = P5E_CPU0_PE1_TX_C_DP<7>
  GND_B41  = GND
  \prsntb0#\  = OCP_SFF_PRSNT0_R_N
  GND_B43  = GND
  PETN8  = P5E_CPU0_PE1_TX_C_DP<8>
  PETP8  = P5E_CPU0_PE1_TX_C_DN<8>
  GND_B46  = GND
  PETN9  = P5E_CPU0_PE1_TX_C_DN<9>
  PETP9  = P5E_CPU0_PE1_TX_C_DP<9>
  GND_B49  = GND
  PETN10  = P5E_CPU0_PE1_TX_C_DP<10>
  PETP10  = P5E_CPU0_PE1_TX_C_DN<10>
  GND_B52  = GND
  PETN11  = P5E_CPU0_PE1_TX_C_DN<11>
  PETP11  = P5E_CPU0_PE1_TX_C_DP<11>
  GND_B55  = GND
  PETN12  = P5E_CPU0_PE1_TX_C_DP<12>
  PETP12  = P5E_CPU0_PE1_TX_C_DN<12>
  GND_B58  = GND
  PETN13  = P5E_CPU0_PE1_TX_C_DN<13>
  PETP13  = P5E_CPU0_PE1_TX_C_DP<13>
  GND_B61  = GND
  PETN14  = P5E_CPU0_PE1_TX_C_DP<14>
  PETP14  = P5E_CPU0_PE1_TX_C_DN<14>
  GND_B64  = GND
  PETN15  = P5E_CPU0_PE1_TX_C_DN<15>
  PETP15  = P5E_CPU0_PE1_TX_C_DP<15>
  GND_B67  = GND
  RFU1_NC_B68  = TP_OCP_SFF_B68
  RFU1_NC_B69  = TP_OCP_SFF_B69
  \prsntb3#\  = OCP_SFF_PRSNT3_R_N
  G1  = GND
  G2  = GND
  G3  = GND
  G4  = GND
  G5  = GND
  \perst2#\  = RST_PERST2_OCP_SFF_N
  \perst3#\  = RST_PERST3_OCP_SFF_N
  \wake#\  = IRQ_LVC3_OCP_SFF_WAKE_N
  RBT_ARB_IN  = OCP_SFF_ISO1_RBT_ARB_IN
  RBT_ARB_OUT  = OCP_SFF_ISO2_RBT_ARB_OUT
  SLOT_ID1  = OCP_SFF_ID1
  RBT_TX_EN  = NCSI_OCP_SFF_TX_EN
  RBT_TXD1  = NCSI_OCP_SFF_TXD1
  RBT_TXD0  = NCSI_OCP_SFF_TXD0
  GND_OA10  = GND
  REFCLKN3  = CLK_100M_OCP_SFF_3_DN
  REFCLKP3  = CLK_100M_OCP_SFF_3_DP
  GND_OA13  = GND
  RBT_CLK_IN  = CLK_50M_NCSI_OCP_SFF_ISO
  NIC_PWR_GOOD  = FM_OCP_SFF_PWR_GOOD
  MAIN_PWR_EN  = OCP_SFF_MAIN_PWR_EN_R
  \ld#\  = SGPIO_OCP_SFF_LD_N
  DATA_IN  = SGPIO_OCP_SFF_DATAIN
  DATA_OUT  = SGPIO_OCP_SFF_DATAOUT
  CLK  = SGPIO_OCP_SFF_CLK
  SLOT_ID0  = OCP_SFF_ID0
  RBT_RXD1  = NCSI_OCP_SFF_RXD1
  RBT_RXD0  = NCSI_OCP_SFF_RXD0
  GND_OB10  = GND
  REFCLKN2  = CLK_100M_OCP_SFF_2_DN
  REFCLKP2  = CLK_100M_OCP_SFF_2_DP
  GND_OB13  = GND
  RBT_CRS_DV  = NCSI_OCP_SFF_CRS_DV

(kicad_pcb
	(version 20260206)
	(generator "pcbnew")
	(generator_version "10.0")
	(general
		(thickness 1.6)
		(legacy_teardrops no)
	)
	(paper "A4")
	(title_block
		(title "03242023_DA0F0TMBIJ0_F0T_Motherboard_J_brd_V01_OCP.brd")
		(comment 1 "Grand Teton / footprint 2414 of 6105 (J37), pads 134-175 of 175")
	)
	(layers
		(0 "F.Cu" signal "TOP")
		(4 "In1.Cu" signal "GND")
		(6 "In2.Cu" signal "IN1")
		(8 "In3.Cu" signal "GND1")
		(10 "In4.Cu" signal "IN2")
		(12 "In5.Cu" signal "GND2")
		(14 "In6.Cu" signal "IN3")
		(16 "In7.Cu" signal "GND3")
		(18 "In8.Cu" signal "VCC")
		(20 "In9.Cu" signal "VCC1")
		(22 "In10.Cu" signal "GND4")
		(24 "In11.Cu" signal "IN4")
		(26 "In12.Cu" signal "GND5")
		(28 "In13.Cu" signal "IN5")
		(30 "In14.Cu" signal "GND6")
		(32 "In15.Cu" signal "IN6")
		(34 "In16.Cu" signal "GND7")
		(2 "B.Cu" signal "BOTTOM")
		(9 "F.Adhes" user "F.Adhesive")
		(11 "B.Adhes" user "B.Adhesive")
		(13 "F.Paste" user "Package Geometry/Pastemask Top")
		(15 "B.Paste" user "Package Geometry/Pastemask Bottom")
		(5 "F.SilkS" user "Ref Des/Silkscreen Top")
		(7 "B.SilkS" user "Ref Des/Silkscreen Bottom")
		(1 "F.Mask" user "Board Geometry/Soldermask Top")
		(3 "B.Mask" user "Board Geometry/Soldermask Bottom")
		(17 "Dwgs.User" user "User.Drawings")
		(19 "Cmts.User" user "User.Comments")
		(21 "Eco1.User" user "User.Eco1")
		(23 "Eco2.User" user "User.Eco2")
		(25 "Edge.Cuts" user "Board Geometry/Outline")
		(27 "Margin" user)
		(31 "F.CrtYd" user "Package Geometry/Place Bound Top")
		(29 "B.CrtYd" user "Package Geometry/Place Bound Bottom")
		(35 "F.Fab" user "Ref Des/Assembly Top")
		(33 "B.Fab" user "Ref Des/Assembly Bottom")
	)
	(footprint ""
		(layer "F.Cu")
		(at 421.901874 -5.569966 -90)
		(property "Reference" "J37"
			(at -16.985996 31.63951 0)
			(unlocked yes)
			(layer "F.SilkS")
			(effects
				(font
					(size 0.7874 0.5842)
					(thickness 0.1524)
				)
				(justify left)
			)
		)
		(property "Value" ""
			(at 0 0 270)
			(layer "F.Fab")
			(effects
				(font
					(size 1.27 1.27)
				)
			)
		)
		(duplicate_pad_numbers_are_jumpers no)
		(pad "B62" smd rect
			(at -5.700014 25.854914 180)
			(size 0.381 1.4478)
			(layers "F.Cu" "F.Mask" "F.Paste")
			(net "P5E_CPU0_PE1_TX_C_DP<14>")
		)
		(pad "B63" smd rect
			(at -5.700014 26.455116 180)
			(size 0.381 1.4478)
			(layers "F.Cu" "F.Mask" "F.Paste")
			(net "P5E_CPU0_PE1_TX_C_DN<14>")
		)
		(pad "B64" smd rect
			(at -5.700014 27.055064 180)
			(size 0.381 1.4478)
			(layers "F.Cu" "F.Mask" "F.Paste")
			(net "GND")
		)
		(pad "B65" smd rect
			(at -5.700014 27.655012 180)
			(size 0.381 1.4478)
			(layers "F.Cu" "F.Mask" "F.Paste")
			(net "P5E_CPU0_PE1_TX_C_DN<15>")
		)
		(pad "B66" smd rect
			(at -5.700014 28.25496 180)
			(size 0.381 1.4478)
			(layers "F.Cu" "F.Mask" "F.Paste")
			(net "P5E_CPU0_PE1_TX_C_DP<15>")
		)
		(pad "B67" smd rect
			(at -5.700014 28.854908 180)
			(size 0.381 1.4478)
			(layers "F.Cu" "F.Mask" "F.Paste")
			(net "GND")
		)
		(pad "B68" smd rect
			(at -5.700014 29.45511 180)
			(size 0.381 1.4478)
			(layers "F.Cu" "F.Mask" "F.Paste")
			(net "TP_OCP_SFF_B68")
		)
		(pad "B69" smd rect
			(at -5.700014 30.055058 180)
			(size 0.381 1.4478)
			(layers "F.Cu" "F.Mask" "F.Paste")
			(net "TP_OCP_SFF_B69")
		)
		(pad "B70" smd rect
			(at -5.700014 30.655006 180)
			(size 0.381 1.4478)
			(layers "F.Cu" "F.Mask" "F.Paste")
			(net "OCP_SFF_PRSNT3_R_N")
		)
		(pad "G1" thru_hole circle
			(at 2.400046 -32.759904 180)
			(size 1.6256 1.6256)
			(drill 1.1176)
			(layers "*.Cu" "*.Mask")
			(remove_unused_layers no)
			(net "GND")
			(clearance 0)
		)
		(pad "G2" thru_hole circle
			(at 2.400046 -20.379944 180)
			(size 1.6256 1.6256)
			(drill 1.1176)
			(layers "*.Cu" "*.Mask")
			(remove_unused_layers no)
			(net "GND")
			(clearance 0)
		)
		(pad "G3" thru_hole circle
			(at 2.400046 0 180)
			(size 1.6256 1.6256)
			(drill 1.1176)
			(layers "*.Cu" "*.Mask")
			(remove_unused_layers no)
			(net "GND")
			(clearance 0)
		)
		(pad "G4" thru_hole circle
			(at 2.400046 12.5349 180)
			(size 1.6256 1.6256)
			(drill 1.1176)
			(layers "*.Cu" "*.Mask")
			(remove_unused_layers no)
			(net "GND")
			(clearance 0)
		)
		(pad "G5" thru_hole circle
			(at 2.400046 32.759904 180)
			(size 1.6256 1.6256)
			(drill 1.1176)
			(layers "*.Cu" "*.Mask")
			(remove_unused_layers no)
			(net "GND")
			(clearance 0)
		)
		(pad "OA1" smd rect
			(at -2.750058 -30.660086 180)
			(size 0.381 1.4478)
			(layers "F.Cu" "F.Mask" "F.Paste")
			(net "RST_PERST2_OCP_SFF_N")
		)
		(pad "OA2" smd rect
			(at -2.750058 -30.059884 180)
			(size 0.381 1.4478)
			(layers "F.Cu" "F.Mask" "F.Paste")
			(net "RST_PERST3_OCP_SFF_N")
		)
		(pad "OA3" smd rect
			(at -2.750058 -29.459936 180)
			(size 0.381 1.4478)
			(layers "F.Cu" "F.Mask" "F.Paste")
			(net "IRQ_LVC3_OCP_SFF_WAKE_N")
		)
		(pad "OA4" smd rect
			(at -2.750058 -28.859988 180)
			(size 0.381 1.4478)
			(layers "F.Cu" "F.Mask" "F.Paste")
			(net "OCP_SFF_ISO1_RBT_ARB_IN")
		)
		(pad "OA5" smd rect
			(at -2.750058 -28.26004 180)
			(size 0.381 1.4478)
			(layers "F.Cu" "F.Mask" "F.Paste")
			(net "OCP_SFF_ISO2_RBT_ARB_OUT")
		)
		(pad "OA6" smd rect
			(at -2.750058 -27.660092 180)
			(size 0.381 1.4478)
			(layers "F.Cu" "F.Mask" "F.Paste")
			(net "OCP_SFF_ID1")
		)
		(pad "OA7" smd rect
			(at -2.750058 -27.05989 180)
			(size 0.381 1.4478)
			(layers "F.Cu" "F.Mask" "F.Paste")
			(net "NCSI_OCP_SFF_TX_EN")
		)
		(pad "OA8" smd rect
			(at -2.750058 -26.459942 180)
			(size 0.381 1.4478)
			(layers "F.Cu" "F.Mask" "F.Paste")
			(net "NCSI_OCP_SFF_TXD1")
		)
		(pad "OA9" smd rect
			(at -2.750058 -25.859994 180)
			(size 0.381 1.4478)
			(layers "F.Cu" "F.Mask" "F.Paste")
			(net "NCSI_OCP_SFF_TXD0")
		)
		(pad "OA10" smd rect
			(at -2.750058 -25.260046 180)
			(size 0.381 1.4478)
			(layers "F.Cu" "F.Mask" "F.Paste")
			(net "GND")
		)
		(pad "OA11" smd rect
			(at -2.750058 -24.660098 180)
			(size 0.381 1.4478)
			(layers "F.Cu" "F.Mask" "F.Paste")
			(net "CLK_100M_OCP_SFF_3_DN")
		)
		(pad "OA12" smd rect
			(at -2.750058 -24.059896 180)
			(size 0.381 1.4478)
			(layers "F.Cu" "F.Mask" "F.Paste")
			(net "CLK_100M_OCP_SFF_3_DP")
		)
		(pad "OA13" smd rect
			(at -2.750058 -23.459948 180)
			(size 0.381 1.4478)
			(layers "F.Cu" "F.Mask" "F.Paste")
			(net "GND")
		)
		(pad "OA14" smd rect
			(at -2.750058 -22.86 180)
			(size 0.381 1.4478)
			(layers "F.Cu" "F.Mask" "F.Paste")
			(net "CLK_50M_NCSI_OCP_SFF_ISO")
		)
		(pad "OB1" smd rect
			(at -5.700014 -30.660086 180)
			(size 0.381 1.4478)
			(layers "F.Cu" "F.Mask" "F.Paste")
			(net "FM_OCP_SFF_PWR_GOOD")
		)
		(pad "OB2" smd rect
			(at -5.700014 -30.059884 180)
			(size 0.381 1.4478)
			(layers "F.Cu" "F.Mask" "F.Paste")
			(net "OCP_SFF_MAIN_PWR_EN_R")
		)
		(pad "OB3" smd rect
			(at -5.700014 -29.459936 180)
			(size 0.381 1.4478)
			(layers "F.Cu" "F.Mask" "F.Paste")
			(net "SGPIO_OCP_SFF_LD_N")
		)
		(pad "OB4" smd rect
			(at -5.700014 -28.859988 180)
			(size 0.381 1.4478)
			(layers "F.Cu" "F.Mask" "F.Paste")
			(net "SGPIO_OCP_SFF_DATAIN")
		)
		(pad "OB5" smd rect
			(at -5.700014 -28.26004 180)
			(size 0.381 1.4478)
			(layers "F.Cu" "F.Mask" "F.Paste")
			(net "SGPIO_OCP_SFF_DATAOUT")
		)
		(pad "OB6" smd rect
			(at -5.700014 -27.660092 180)
			(size 0.381 1.4478)
			(layers "F.Cu" "F.Mask" "F.Paste")
			(net "SGPIO_OCP_SFF_CLK")
		)
		(pad "OB7" smd rect
			(at -5.700014 -27.05989 180)
			(size 0.381 1.4478)
			(layers "F.Cu" "F.Mask" "F.Paste")
			(net "OCP_SFF_ID0")
		)
		(pad "OB8" smd rect
			(at -5.700014 -26.459942 180)
			(size 0.381 1.4478)
			(layers "F.Cu" "F.Mask" "F.Paste")
			(net "NCSI_OCP_SFF_RXD1")
		)
		(pad "OB9" smd rect
			(at -5.700014 -25.859994 180)
			(size 0.381 1.4478)
			(layers "F.Cu" "F.Mask" "F.Paste")
			(net "NCSI_OCP_SFF_RXD0")
		)
		(pad "OB10" smd rect
			(at -5.700014 -25.260046 180)
			(size 0.381 1.4478)
			(layers "F.Cu" "F.Mask" "F.Paste")
			(net "GND")
		)
		(pad "OB11" smd rect
			(at -5.700014 -24.660098 180)
			(size 0.381 1.4478)
			(layers "F.Cu" "F.Mask" "F.Paste")
			(net "CLK_100M_OCP_SFF_2_DN")
		)
		(pad "OB12" smd rect
			(at -5.700014 -24.059896 180)
			(size 0.381 1.4478)
			(layers "F.Cu" "F.Mask" "F.Paste")
			(net "CLK_100M_OCP_SFF_2_DP")
		)
		(pad "OB13" smd rect
			(at -5.700014 -23.459948 180)
			(size 0.381 1.4478)
			(layers "F.Cu" "F.Mask" "F.Paste")
			(net "GND")
		)
		(pad "OB14" smd rect
			(at -5.700014 -22.86 180)
			(size 0.381 1.4478)
			(layers "F.Cu" "F.Mask" "F.Paste")
			(net "NCSI_OCP_SFF_CRS_DV")
		)
	)
)
